(kicad_pcb
	(version 20241229)
	(generator "pcbnew")
	(generator_version "9.0")
	(general
		(thickness 1.62)
		(legacy_teardrops no)
	)
	(paper "A3")
	(title_block
		(title "COM Express 7 Baseboard")
		(date "2025-02-04")
		(rev "1.1.2")
		(company "Antmicro Ltd")
		(comment 1 "www.antmicro.com")
		(comment 9 "footprints 586-590 of 802")
	)
	(layers
		(0 "F.Cu" signal)
		(4 "In1.Cu" signal)
		(6 "In2.Cu" signal)
		(8 "In3.Cu" signal)
		(10 "In4.Cu" signal)
		(12 "In5.Cu" signal)
		(14 "In6.Cu" signal)
		(2 "B.Cu" signal)
		(9 "F.Adhes" user "F.Adhesive")
		(11 "B.Adhes" user "B.Adhesive")
		(13 "F.Paste" user)
		(15 "B.Paste" user)
		(5 "F.SilkS" user "F.Silkscreen")
		(7 "B.SilkS" user "B.Silkscreen")
		(1 "F.Mask" user)
		(3 "B.Mask" user)
		(17 "Dwgs.User" user "User.Drawings")
		(19 "Cmts.User" user "User.Comments")
		(21 "Eco1.User" user "User.Eco1")
		(23 "Eco2.User" user "User.Eco2")
		(25 "Edge.Cuts" user)
		(27 "Margin" user)
		(31 "F.CrtYd" user "F.Courtyard")
		(29 "B.CrtYd" user "B.Courtyard")
		(35 "F.Fab" user)
		(33 "B.Fab" user)
	)
	(footprint "antmicro-footprints:C_0402_1005Metric"
		(layer "B.Cu")
		(at 132.29 132.36 -90)
		(descr "Capacitor SMD 0402")
		(tags "capacitor SMD 0402")
		(property "Reference" "C198"
			(at -3.7 -0.41 90)
			(layer "B.SilkS")
			(effects
				(font
					(size 0.7 0.7)
					(thickness 0.15)
				)
				(justify left bottom mirror)
			)
		)
		(property "Value" "C_100n_0402"
			(at -1.022927 -2.155213 90)
			(layer "B.Fab")
			(effects
				(font
					(size 0.7 0.7)
					(thickness 0.15)
				)
				(justify left bottom mirror)
			)
		)
		(property "Datasheet" "https://www.murata.com/products/productdetail?partno=GRM155R61H104KE14%23"
			(at 0 0 270)
			(layer "F.Fab")
			(hide yes)
			(effects
				(font
					(size 1.27 1.27)
					(thickness 0.15)
				)
			)
		)
		(property "Author" "Antmicro"
			(at -0.07 264.65 0)
			(layer "B.Fab")
			(hide yes)
			(effects
				(font
					(size 1 1)
					(thickness 0.15)
				)
				(justify mirror)
			)
		)
		(property "Dielectric" "X5R"
			(at -0.07 264.65 0)
			(layer "B.Fab")
			(hide yes)
			(effects
				(font
					(size 1 1)
					(thickness 0.15)
				)
				(justify mirror)
			)
		)
		(property "License" "Apache-2.0"
			(at -0.07 264.65 0)
			(layer "B.Fab")
			(hide yes)
			(effects
				(font
					(size 1 1)
					(thickness 0.15)
				)
				(justify mirror)
			)
		)
		(property "MPN" "GRM155R61H104KE14D"
			(at -0.07 264.65 0)
			(layer "B.Fab")
			(hide yes)
			(effects
				(font
					(size 1 1)
					(thickness 0.15)
				)
				(justify mirror)
			)
		)
		(property "Manufacturer" "Murata"
			(at -0.07 264.65 0)
			(layer "B.Fab")
			(hide yes)
			(effects
				(font
					(size 1 1)
					(thickness 0.15)
				)
				(justify mirror)
			)
		)
		(property "Public" "False"
			(at -0.07 264.65 0)
			(layer "B.Fab")
			(hide yes)
			(effects
				(font
					(size 1 1)
					(thickness 0.15)
				)
				(justify mirror)
			)
		)
		(property "Val" "100n"
			(at -0.07 264.65 0)
			(layer "B.Fab")
			(hide yes)
			(effects
				(font
					(size 1 1)
					(thickness 0.15)
				)
				(justify mirror)
			)
		)
		(property "Voltage" "50V"
			(at -0.07 264.65 0)
			(layer "B.Fab")
			(hide yes)
			(effects
				(font
					(size 1 1)
					(thickness 0.15)
				)
				(justify mirror)
			)
		)
		(sheetname "KR to SFI #2")
		(sheetfile "kr_sfi.kicad_sch")
		(attr smd)
		(fp_rect
			(start -0.925 0.47)
			(end 0.925 -0.47)
			(stroke
				(width 0.05)
				(type default)
			)
			(fill no)
			(layer "B.CrtYd")
		)
		(fp_line
			(start -0.494 0.25)
			(end -0.494 -0.248)
			(stroke
				(width 0.15)
				(type solid)
			)
			(layer "B.Fab")
		)
		(fp_line
			(start 0.504 0.25)
			(end -0.494 0.25)
			(stroke
				(width 0.15)
				(type solid)
			)
			(layer "B.Fab")
		)
		(fp_line
			(start -0.494 -0.248)
			(end 0.504 -0.248)
			(stroke
				(width 0.15)
				(type solid)
			)
			(layer "B.Fab")
		)
		(fp_line
			(start 0.504 -0.248)
			(end 0.504 0.25)
			(stroke
				(width 0.15)
				(type solid)
			)
			(layer "B.Fab")
		)
		(pad "1" smd roundrect
			(at -0.48 0 270)
			(size 0.59 0.64)
			(layers "B.Cu" "B.Mask" "B.Paste")
			(roundrect_rratio 0.25)
			(net 1 "GND")
			(pintype "passive")
			(teardrops
				(best_length_ratio 0.2)
				(max_length 1)
				(best_width_ratio 0.9)
				(max_width 2)
				(curved_edges yes)
				(filter_ratio 0.9)
				(enabled yes)
				(allow_two_segments yes)
				(prefer_zone_connections yes)
			)
		)
		(pad "2" smd roundrect
			(at 0.48 0 270)
			(size 0.59 0.64)
			(layers "B.Cu" "B.Mask" "B.Paste")
			(roundrect_rratio 0.25)
			(net 74 "+1V0")
			(pintype "passive")
			(teardrops
				(best_length_ratio 0.2)
				(max_length 1)
				(best_width_ratio 0.9)
				(max_width 2)
				(curved_edges yes)
				(filter_ratio 0.9)
				(enabled yes)
				(allow_two_segments yes)
				(prefer_zone_connections yes)
			)
		)
	)
	(footprint "antmicro-footprints:C_0402_1005Metric"
		(layer "B.Cu")
		(at 256.350707 78.135)
		(descr "Capacitor SMD 0402")
		(tags "capacitor SMD 0402")
		(property "Reference" "C84"
			(at -1.079999 1.375 0)
			(layer "B.SilkS")
			(effects
				(font
					(size 0.7 0.7)
					(thickness 0.15)
				)
				(justify right bottom mirror)
			)
		)
		(property "Value" "C_100n_0402"
			(at -1.022927 -2.155213 0)
			(layer "B.Fab")
			(effects
				(font
					(size 0.7 0.7)
					(thickness 0.15)
				)
				(justify right bottom mirror)
			)
		)
		(property "Datasheet" "https://www.murata.com/products/productdetail?partno=GRM155R61H104KE14%23"
			(at 0 0 0)
			(layer "F.Fab")
			(hide yes)
			(effects
				(font
					(size 1.27 1.27)
					(thickness 0.15)
				)
			)
		)
		(property "Author" "Antmicro"
			(at 0 0 0)
			(layer "B.Fab")
			(hide yes)
			(effects
				(font
					(size 1 1)
					(thickness 0.15)
				)
				(justify mirror)
			)
		)
		(property "Dielectric" "X5R"
			(at 0 0 0)
			(layer "B.Fab")
			(hide yes)
			(effects
				(font
					(size 1 1)
					(thickness 0.15)
				)
				(justify mirror)
			)
		)
		(property "License" "Apache-2.0"
			(at 0 0 0)
			(layer "B.Fab")
			(hide yes)
			(effects
				(font
					(size 1 1)
					(thickness 0.15)
				)
				(justify mirror)
			)
		)
		(property "MPN" "GRM155R61H104KE14D"
			(at 0 0 0)
			(layer "B.Fab")
			(hide yes)
			(effects
				(font
					(size 1 1)
					(thickness 0.15)
				)
				(justify mirror)
			)
		)
		(property "Manufacturer" "Murata"
			(at 0 0 0)
			(layer "B.Fab")
			(hide yes)
			(effects
				(font
					(size 1 1)
					(thickness 0.15)
				)
				(justify mirror)
			)
		)
		(property "Public" "False"
			(at 0 0 0)
			(layer "B.Fab")
			(hide yes)
			(effects
				(font
					(size 1 1)
					(thickness 0.15)
				)
				(justify mirror)
			)
		)
		(property "Val" "100n"
			(at 0 0 0)
			(layer "B.Fab")
			(hide yes)
			(effects
				(font
					(size 1 1)
					(thickness 0.15)
				)
				(justify mirror)
			)
		)
		(property "Voltage" "50V"
			(at 0 0 0)
			(layer "B.Fab")
			(hide yes)
			(effects
				(font
					(size 1 1)
					(thickness 0.15)
				)
				(justify mirror)
			)
		)
		(sheetname "Misc")
		(sheetfile "misc.kicad_sch")
		(attr smd)
		(fp_rect
			(start -0.925 0.47)
			(end 0.925 -0.47)
			(stroke
				(width 0.05)
				(type default)
			)
			(fill no)
			(layer "B.CrtYd")
		)
		(fp_line
			(start -0.494 -0.248)
			(end 0.504 -0.248)
			(stroke
				(width 0.15)
				(type solid)
			)
			(layer "B.Fab")
		)
		(fp_line
			(start -0.494 0.25)
			(end -0.494 -0.248)
			(stroke
				(width 0.15)
				(type solid)
			)
			(layer "B.Fab")
		)
		(fp_line
			(start 0.504 -0.248)
			(end 0.504 0.25)
			(stroke
				(width 0.15)
				(type solid)
			)
			(layer "B.Fab")
		)
		(fp_line
			(start 0.504 0.25)
			(end -0.494 0.25)
			(stroke
				(width 0.15)
				(type solid)
			)
			(layer "B.Fab")
		)
		(pad "1" smd roundrect
			(at -0.48 0)
			(size 0.59 0.64)
			(layers "B.Cu" "B.Mask" "B.Paste")
			(roundrect_rratio 0.25)
			(net 1 "GND")
			(pintype "passive")
			(teardrops
				(best_length_ratio 0.2)
				(max_length 1)
				(best_width_ratio 0.9)
				(max_width 2)
				(curved_edges yes)
				(filter_ratio 0.9)
				(enabled yes)
				(allow_two_segments yes)
				(prefer_zone_connections yes)
			)
		)
		(pad "2" smd roundrect
			(at 0.48 0)
			(size 0.59 0.64)
			(layers "B.Cu" "B.Mask" "B.Paste")
			(roundrect_rratio 0.25)
			(net 2 "+3V3")
			(pintype "passive")
			(teardrops
				(best_length_ratio 0.2)
				(max_length 1)
				(best_width_ratio 0.9)
				(max_width 2)
				(curved_edges yes)
				(filter_ratio 0.9)
				(enabled yes)
				(allow_two_segments yes)
				(prefer_zone_connections yes)
			)
		)
	)
	(footprint "antmicro-footprints:R_0402_1005Metric"
		(layer "B.Cu")
		(at 139.74 141.36)
		(descr "Resistor SMD 0402")
		(tags "resistor SMD 0402")
		(property "Reference" "R294"
			(at -3.64 0.75 0)
			(layer "B.SilkS")
			(effects
				(font
					(size 0.7 0.7)
					(thickness 0.15)
				)
				(justify right bottom mirror)
			)
		)
		(property "Value" "R_10k_0402"
			(at -1.011843 -1.772047 0)
			(layer "B.Fab")
			(effects
				(font
					(size 0.7 0.7)
					(thickness 0.15)
				)
				(justify right bottom mirror)
			)
		)
		(property "Datasheet" "https://www.bourns.com/docs/product-datasheets/cr.pdf"
			(at 0 0 0)
			(layer "F.Fab")
			(hide yes)
			(effects
				(font
					(size 1.27 1.27)
					(thickness 0.15)
				)
			)
		)
		(property "Author" "Antmicro"
			(at 0 0 0)
			(layer "B.Fab")
			(hide yes)
			(effects
				(font
					(size 1 1)
					(thickness 0.15)
				)
				(justify mirror)
			)
		)
		(property "License" "Apache-2.0"
			(at 0 0 0)
			(layer "B.Fab")
			(hide yes)
			(effects
				(font
					(size 1 1)
					(thickness 0.15)
				)
				(justify mirror)
			)
		)
		(property "MPN" "CR0402-FX-1002GLF"
			(at 0 0 0)
			(layer "B.Fab")
			(hide yes)
			(effects
				(font
					(size 1 1)
					(thickness 0.15)
				)
				(justify mirror)
			)
		)
		(property "Manufacturer" "Bourns"
			(at 0 0 0)
			(layer "B.Fab")
			(hide yes)
			(effects
				(font
					(size 1 1)
					(thickness 0.15)
				)
				(justify mirror)
			)
		)
		(property "Public" "False"
			(at 0 0 0)
			(layer "B.Fab")
			(hide yes)
			(effects
				(font
					(size 1 1)
					(thickness 0.15)
				)
				(justify mirror)
			)
		)
		(property "Tolerance" "1%"
			(at 0 0 0)
			(layer "B.Fab")
			(hide yes)
			(effects
				(font
					(size 1 1)
					(thickness 0.15)
				)
				(justify mirror)
			)
		)
		(property "Val" "10k"
			(at 0 0 0)
			(layer "B.Fab")
			(hide yes)
			(effects
				(font
					(size 1 1)
					(thickness 0.15)
				)
				(justify mirror)
			)
		)
		(sheetname "KR to SFI #2")
		(sheetfile "kr_sfi.kicad_sch")
		(attr smd dnp)
		(fp_rect
			(start -0.925 0.47)
			(end 0.925 -0.47)
			(stroke
				(width 0.05)
				(type default)
			)
			(fill no)
			(layer "B.CrtYd")
		)
		(fp_rect
			(start -0.5 0.25)
			(end 0.5 -0.25)
			(stroke
				(width 0.15)
				(type solid)
			)
			(fill no)
			(layer "B.Fab")
		)
		(pad "1" smd roundrect
			(at -0.48 0)
			(size 0.59 0.64)
			(layers "B.Cu" "B.Mask" "B.Paste")
			(roundrect_rratio 0.25)
			(net 676 "Net-(U45C-PRTAD0)")
			(pintype "passive")
			(teardrops
				(best_length_ratio 0.2)
				(max_length 1)
				(best_width_ratio 0.9)
				(max_width 2)
				(curved_edges yes)
				(filter_ratio 0.9)
				(enabled yes)
				(allow_two_segments yes)
				(prefer_zone_connections yes)
			)
		)
		(pad "2" smd roundrect
			(at 0.48 0)
			(size 0.59 0.64)
			(layers "B.Cu" "B.Mask" "B.Paste")
			(roundrect_rratio 0.25)
			(net 78 "+1V8")
			(pintype "passive")
			(teardrops
				(best_length_ratio 0.2)
				(max_length 1)
				(best_width_ratio 0.9)
				(max_width 2)
				(curved_edges yes)
				(filter_ratio 0.9)
				(enabled yes)
				(allow_two_segments yes)
				(prefer_zone_connections yes)
			)
		)
	)
	(footprint "antmicro-footprints:R_0402_1005Metric"
		(layer "B.Cu")
		(at 116.45 69.86 -90)
		(descr "Resistor SMD 0402")
		(tags "resistor SMD 0402")
		(property "Reference" "R138"
			(at 0.8 -0.45 90)
			(layer "B.SilkS")
			(effects
				(font
					(size 0.7 0.7)
					(thickness 0.15)
				)
				(justify left bottom mirror)
			)
		)
		(property "Value" "R_220R_0402"
			(at -1.011843 -1.772047 90)
			(layer "B.Fab")
			(effects
				(font
					(size 0.7 0.7)
					(thickness 0.15)
				)
				(justify left bottom mirror)
			)
		)
		(property "Datasheet" "https://www.bourns.com/docs/product-datasheets/cr.pdf"
			(at 0 0 270)
			(layer "F.Fab")
			(hide yes)
			(effects
				(font
					(size 1.27 1.27)
					(thickness 0.15)
				)
			)
		)
		(property "Author" "Antmicro"
			(at 46.59 186.31 0)
			(layer "B.Fab")
			(hide yes)
			(effects
				(font
					(size 1 1)
					(thickness 0.15)
				)
				(justify mirror)
			)
		)
		(property "License" "Apache-2.0"
			(at 46.59 186.31 0)
			(layer "B.Fab")
			(hide yes)
			(effects
				(font
					(size 1 1)
					(thickness 0.15)
				)
				(justify mirror)
			)
		)
		(property "MPN" "CR0402-FX-2200GLF"
			(at 46.59 186.31 0)
			(layer "B.Fab")
			(hide yes)
			(effects
				(font
					(size 1 1)
					(thickness 0.15)
				)
				(justify mirror)
			)
		)
		(property "Manufacturer" "Bourns"
			(at 46.59 186.31 0)
			(layer "B.Fab")
			(hide yes)
			(effects
				(font
					(size 1 1)
					(thickness 0.15)
				)
				(justify mirror)
			)
		)
		(property "Public" "False"
			(at 46.59 186.31 0)
			(layer "B.Fab")
			(hide yes)
			(effects
				(font
					(size 1 1)
					(thickness 0.15)
				)
				(justify mirror)
			)
		)
		(property "Tolerance" "1%"
			(at 46.59 186.31 0)
			(layer "B.Fab")
			(hide yes)
			(effects
				(font
					(size 1 1)
					(thickness 0.15)
				)
				(justify mirror)
			)
		)
		(property "Val" "220R"
			(at 46.59 186.31 0)
			(layer "B.Fab")
			(hide yes)
			(effects
				(font
					(size 1 1)
					(thickness 0.15)
				)
				(justify mirror)
			)
		)
		(sheetname "M.2 key E")
		(sheetfile "m2keye.kicad_sch")
		(attr smd)
		(fp_rect
			(start -0.925 0.47)
			(end 0.925 -0.47)
			(stroke
				(width 0.05)
				(type default)
			)
			(fill no)
			(layer "B.CrtYd")
		)
		(fp_rect
			(start -0.5 0.25)
			(end 0.5 -0.25)
			(stroke
				(width 0.15)
				(type solid)
			)
			(fill no)
			(layer "B.Fab")
		)
		(pad "1" smd roundrect
			(at -0.48 0 270)
			(size 0.59 0.64)
			(layers "B.Cu" "B.Mask" "B.Paste")
			(roundrect_rratio 0.25)
			(net 937 "Net-(D15-A)")
			(pintype "passive")
			(teardrops
				(best_length_ratio 0.2)
				(max_length 1)
				(best_width_ratio 0.9)
				(max_width 2)
				(curved_edges yes)
				(filter_ratio 0.9)
				(enabled yes)
				(allow_two_segments yes)
				(prefer_zone_connections yes)
			)
		)
		(pad "2" smd roundrect
			(at 0.48 0 270)
			(size 0.59 0.64)
			(layers "B.Cu" "B.Mask" "B.Paste")
			(roundrect_rratio 0.25)
			(net 2 "+3V3")
			(pintype "passive")
			(teardrops
				(best_length_ratio 0.2)
				(max_length 1)
				(best_width_ratio 0.9)
				(max_width 2)
				(curved_edges yes)
				(filter_ratio 0.9)
				(enabled yes)
				(allow_two_segments yes)
				(prefer_zone_connections yes)
			)
		)
	)
	(footprint "antmicro-footprints:R_0402_1005Metric"
		(layer "B.Cu")
		(at 157.9 139.36)
		(descr "Resistor SMD 0402")
		(tags "resistor SMD 0402")
		(property "Reference" "R264"
			(at 0.85 0.45 0)
			(layer "B.SilkS")
			(effects
				(font
					(size 0.7 0.7)
					(thickness 0.15)
				)
				(justify right bottom mirror)
			)
		)
		(property "Value" "R_10k_0402"
			(at -1.011843 -1.772047 0)
			(layer "B.Fab")
			(effects
				(font
					(size 0.7 0.7)
					(thickness 0.15)
				)
				(justify right bottom mirror)
			)
		)
		(property "Datasheet" "https://www.bourns.com/docs/product-datasheets/cr.pdf"
			(at 0 0 0)
			(layer "F.Fab")
			(hide yes)
			(effects
				(font
					(size 1.27 1.27)
					(thickness 0.15)
				)
			)
		)
		(property "Author" "Antmicro"
			(at 0 0 0)
			(layer "B.Fab")
			(hide yes)
			(effects
				(font
					(size 1 1)
					(thickness 0.15)
				)
				(justify mirror)
			)
		)
		(property "License" "Apache-2.0"
			(at 0 0 0)
			(layer "B.Fab")
			(hide yes)
			(effects
				(font
					(size 1 1)
					(thickness 0.15)
				)
				(justify mirror)
			)
		)
		(property "MPN" "CR0402-FX-1002GLF"
			(at 0 0 0)
			(layer "B.Fab")
			(hide yes)
			(effects
				(font
					(size 1 1)
					(thickness 0.15)
				)
				(justify mirror)
			)
		)
		(property "Manufacturer" "Bourns"
			(at 0 0 0)
			(layer "B.Fab")
			(hide yes)
			(effects
				(font
					(size 1 1)
					(thickness 0.15)
				)
				(justify mirror)
			)
		)
		(property "Public" "False"
			(at 0 0 0)
			(layer "B.Fab")
			(hide yes)
			(effects
				(font
					(size 1 1)
					(thickness 0.15)
				)
				(justify mirror)
			)
		)
		(property "Tolerance" "1%"
			(at 0 0 0)
			(layer "B.Fab")
			(hide yes)
			(effects
				(font
					(size 1 1)
					(thickness 0.15)
				)
				(justify mirror)
			)
		)
		(property "Val" "10k"
			(at 0 0 0)
			(layer "B.Fab")
			(hide yes)
			(effects
				(font
					(size 1 1)
					(thickness 0.15)
				)
				(justify mirror)
			)
		)
		(sheetname "KR to SFI #1")
		(sheetfile "kr_sfi.kicad_sch")
		(attr smd)
		(fp_rect
			(start -0.925 0.47)
			(end 0.925 -0.47)
			(stroke
				(width 0.05)
				(type default)
			)
			(fill no)
			(layer "B.CrtYd")
		)
		(fp_rect
			(start -0.5 0.25)
			(end 0.5 -0.25)
			(stroke
				(width 0.15)
				(type solid)
			)
			(fill no)
			(layer "B.Fab")
		)
		(pad "1" smd roundrect
			(at -0.48 0)
			(size 0.59 0.64)
			(layers "B.Cu" "B.Mask" "B.Paste")
			(roundrect_rratio 0.25)
			(net 657 "Net-(U43A-~{PDTRXA})")
			(pintype "passive")
			(teardrops
				(best_length_ratio 0.2)
				(max_length 1)
				(best_width_ratio 0.9)
				(max_width 2)
				(curved_edges yes)
				(filter_ratio 0.9)
				(enabled yes)
				(allow_two_segments yes)
				(prefer_zone_connections yes)
			)
		)
		(pad "2" smd roundrect
			(at 0.48 0)
			(size 0.59 0.64)
			(layers "B.Cu" "B.Mask" "B.Paste")
			(roundrect_rratio 0.25)
			(net 78 "+1V8")
			(pintype "passive")
			(teardrops
				(best_length_ratio 0.2)
				(max_length 1)
				(best_width_ratio 0.9)
				(max_width 2)
				(curved_edges yes)
				(filter_ratio 0.9)
				(enabled yes)
				(allow_two_segments yes)
				(prefer_zone_connections yes)
			)
		)
	)
)
